#ISCELL
  mstr_misc dns *
  *
#ISCELL
  mstr_symbols design_note *
  *
#ISCELL
  mstr_symbols intel_corp_bpage *
  *
#ISCELL
  mstr_standard offpage *
  page182_i100
#CELL
  mstr_discrete res *
  page182_i101
#ISCELL
  mstr_standard offpage *
  page182_i102
#ISCELL
  mstr_standard offpage *
  page182_i103
#CELL
  mstr_discrete res *
  page182_i104
#ISCELL
  mstr_standard offpage *
  page182_i105
#ISCELL
  mstr_standard offpage *
  page182_i106
#CELL
  mstr_discrete res *
  page182_i107
#ISCELL
  mstr_standard offpage *
  page182_i108
#ISCELL
  mstr_standard offpage *
  page182_i109
#CELL
  mstr_discrete res *
  page182_i110
#ISCELL
  mstr_standard offpage *
  page182_i111
#CELL
  mstr_discrete cap *
  page182_i12
#CELL
  mstr_discrete cap *
  page182_i13
#CELL
  mstr_discrete cap *
  page182_i14
#CELL
  mstr_discrete cap *
  page182_i15
#CELL
  mstr_discrete cap *
  page182_i16
#ISCELL
  mstr_symbols gnd *
  page182_i17
#CELL
  mstr_conn conn76_h22707001 *
  page182_i18
#ISCELL
  mstr_symbols gnd *
  page182_i19
#ISCELL
  mstr_standard tap *
  page182_i2
#ISCELL
  mstr_standard offpage *
  page182_i29
#ISCELL
  mstr_standard offpage *
  page182_i30
#ISCELL
  mstr_standard tap *
  page182_i4
#ISCELL
  mstr_standard tap *
  page182_i41
#ISCELL
  mstr_standard tap *
  page182_i42
#ISCELL
  mstr_standard tap *
  page182_i43
#ISCELL
  mstr_standard tap *
  page182_i44
#ISCELL
  mstr_standard tap *
  page182_i45
#ISCELL
  mstr_standard tap *
  page182_i46
#ISCELL
  mstr_standard tap *
  page182_i47
#ISCELL
  mstr_standard tap *
  page182_i48
#CELL
  mstr_discrete cap *
  page182_i49
#ISCELL
  mstr_standard tap *
  page182_i5
#CELL
  mstr_discrete cap *
  page182_i50
#CELL
  mstr_discrete cap *
  page182_i51
#CELL
  mstr_discrete cap *
  page182_i52
#CELL
  mstr_discrete cap *
  page182_i53
#CELL
  mstr_discrete cap *
  page182_i54
#CELL
  mstr_discrete cap *
  page182_i55
#CELL
  mstr_discrete cap *
  page182_i56
#ISCELL
  mstr_standard tap *
  page182_i57
#ISCELL
  mstr_standard tap *
  page182_i58
#ISCELL
  mstr_standard tap *
  page182_i59
#ISCELL
  mstr_standard tap *
  page182_i6
#ISCELL
  mstr_standard tap *
  page182_i60
#ISCELL
  mstr_standard tap *
  page182_i61
#ISCELL
  mstr_standard tap *
  page182_i62
#ISCELL
  mstr_standard tap *
  page182_i63
#ISCELL
  mstr_standard tap *
  page182_i64
#ISCELL
  mstr_standard offpage *
  page182_i65
#ISCELL
  mstr_standard offpage *
  page182_i66
#ISCELL
  mstr_standard tap *
  page182_i67
#ISCELL
  mstr_standard tap *
  page182_i68
#ISCELL
  mstr_standard tap *
  page182_i69
#ISCELL
  mstr_standard tap *
  page182_i7
#ISCELL
  mstr_standard tap *
  page182_i70
#ISCELL
  mstr_standard tap *
  page182_i71
#ISCELL
  mstr_standard tap *
  page182_i72
#ISCELL
  mstr_standard tap *
  page182_i73
#ISCELL
  mstr_standard tap *
  page182_i74
#ISCELL
  mstr_standard tap *
  page182_i8
#CELL
  mstr_discrete cap *
  page182_i81
#ISCELL
  mstr_standard tap *
  page182_i82
#CELL
  mstr_discrete cap *
  page182_i83
#ISCELL
  mstr_standard tap *
  page182_i84
#ISCELL
  mstr_standard offpage *
  page182_i85
#ISCELL
  mstr_standard offpage *
  page182_i86
#ISCELL
  mstr_standard offpage *
  page182_i87
#CELL
  mstr_discrete cap *
  page182_i9
#ISCELL
  mstr_standard offpage *
  page182_i91
#ISCELL
  mstr_standard offpage *
  page182_i92
#ISCELL
  mstr_standard offpage *
  page182_i94
#ISCELL
  mstr_standard offpage *
  page182_i95
#ISCELL
  mstr_standard offpage *
  page182_i96
#CELL
  mstr_discrete res *
  page182_i97
#ISCELL
  mstr_standard offpage *
  page182_i98
#ISCELL
  mstr_standard offpage *
  page182_i99
